FILE_TYPE = MULTI_PHYS_TABLE;

PART 'SCONN20_513860200CV01'

{========================================================================================}
:VALUE                     | PART_TYPE | MATERIAL | PART_NUMBER    = STANDARD | LIFECYCLE      | PART_NUMBER   | JEDEC_TYPE        | DESCRIPTION                          | MANUFTR | MANUF_PN          | RD_CMPLS_LVL | CMPLS_LVL | CLASS | DIP_SMD | FROM_PJ  | DATA                      | FP_ECN                | EE_CHECK_LIST | CREATOR | CREATEDAY  | PSL | STATUS | ESD_CDM | ESD_HBM | ESD_MM | MSD | PIN_LENGTH_LONG_PIN | PIN_LENGTH_SHORT_PIN ;
{========================================================================================}
 'SCONN20_51386-0200C-V01' | 'SMLF'    | 'IO'     | 'DFHD20MS193'(!) = ''       | ''               | 'DFHD20MS193' |'HEADER2X10SBHXB'| 'CONN SMD HEADER 20P 2R MS(P2,H6.4)' | 'ACS'   | '51386-0200C-V01' | 'EP(V1)'     | 'EP(V1)'  | 'IO'  | ''      | 'L19-TH' | 'ACS_51386-0200C-V01.pdf' | '51386-0200C-V01.msg' | ''            | ''      | '20210702' | ''  | ''     | ''      | ''      | ''     | ''  | '38 MILS'           | '38 MILS'           
 'SCONN20_51386-0200C-V01' | 'SMLF'    | 'EMPTY'  | 'DFHD20MS193'(!) = ''       | ''               | 'DFHD20MS193' |'HEADER2X10SBHXB'| 'CONN SMD HEADER 20P 2R MS(P2,H6.4)' | 'ACS'   | '51386-0200C-V01' | 'EP(V1)'     | 'EP(V1)'  | 'IO'  | ''      | 'L19-TH' | 'ACS_51386-0200C-V01.pdf' | '51386-0200C-V01.msg' | ''            | ''      | '20210702' | ''  | ''     | ''      | ''      | ''     | ''  | '38 MILS'           | '38 MILS'           

END_PART

END.

